# TIMECARD (Time Appliance Project (Time Card)) — schematic netlist excerpt (pin names and nets, part order shuffled) for the footprints in the layout excerpt that follows; sources: Cadence DE-HDL packaged netlist, KiCad conversion of R4006-B0001-02_R01.brd

R419  RESISTOR  4.7KOHM 1%  pkg SMC_0402R_H016  page 17 : \1\ = XP3R3V_FPGA ; \2\ = UNNAMED_6_LM75BDPTSSOP8_I81_A0
R20  RESISTOR  4.7KOHM 1%  pkg SMC_0402R_H016  page 17 : \1\ = XP3R3V_FPGA ; \2\ = LM75B_I2C_SDA

(kicad_pcb
	(version 20260206)
	(generator "pcbnew")
	(generator_version "10.0")
	(general
		(thickness 1.6)
		(legacy_teardrops no)
	)
	(paper "A4")
	(title_block
		(title "timecard-production-celestica-r4006 — R4006-B0001-02_R01.brd")
		(comment 1 "Time Appliance Project (Time Card) / footprints 18-19 of 1113")
	)
	(layers
		(0 "F.Cu" signal "TOP")
		(4 "In1.Cu" signal "L02_GND1")
		(6 "In2.Cu" signal "L03_SIG1")
		(8 "In3.Cu" signal "L04_GND2")
		(10 "In4.Cu" signal "L05_VCC1")
		(12 "In5.Cu" signal "L06_VCC2")
		(14 "In6.Cu" signal "L07_GND3")
		(16 "In7.Cu" signal "L08_SIG2")
		(18 "In8.Cu" signal "L09_GND4")
		(2 "B.Cu" signal "BOTTOM")
		(9 "F.Adhes" user "F.Adhesive")
		(11 "B.Adhes" user "B.Adhesive")
		(13 "F.Paste" user "Package Geometry/Pastemask Top")
		(15 "B.Paste" user "Package Geometry/Pastemask Bottom")
		(5 "F.SilkS" user "Ref Des/Silkscreen Top")
		(7 "B.SilkS" user "Ref Des/Silkscreen Bottom")
		(1 "F.Mask" user "Board Geometry/Soldermask Top")
		(3 "B.Mask" user "Board Geometry/Soldermask Bottom")
		(17 "Dwgs.User" user "User.Drawings")
		(19 "Cmts.User" user "User.Comments")
		(21 "Eco1.User" user "User.Eco1")
		(23 "Eco2.User" user "User.Eco2")
		(25 "Edge.Cuts" user "Board Geometry/Outline")
		(27 "Margin" user)
		(31 "F.CrtYd" user "Package Geometry/Place Bound Top")
		(29 "B.CrtYd" user "Package Geometry/Place Bound Bottom")
		(35 "F.Fab" user "Ref Des/Assembly Top")
		(33 "B.Fab" user "Ref Des/Assembly Bottom")
	)
	(footprint ""
		(layer "F.Cu")
		(at 150.749 -28.575 180)
		(property "Reference" "R20"
			(at 1.143 1.99263 0)
			(unlocked yes)
			(layer "F.SilkS")
			(effects
				(font
					(size 0.7874 0.5842)
					(thickness 0.1524)
				)
			)
		)
		(property "Value" "VAL*"
			(at 0.02032 2.13233 180)
			(unlocked yes)
			(layer "F.Fab")
			(hide yes)
			(effects
				(font
					(size 0.7874 0.5842)
					(thickness 0.1524)
				)
			)
		)
		(property "Tolerance" "TOL*"
			(at 0.044704 3.05435 180)
			(unlocked yes)
			(layer "Cmts.User")
			(hide yes)
			(effects
				(font
					(size 0.7874 0.5842)
					(thickness 0.1524)
				)
			)
		)
		(property "User Part Number" "PARTNUM*"
			(at 0.02032 4.024884 180)
			(unlocked yes)
			(layer "Cmts.User")
			(hide yes)
			(effects
				(font
					(size 0.7874 0.5842)
					(thickness 0.1524)
				)
			)
		)
		(property "Device Type" "RESISTOR-G155-14701-01,4.7KOHMA"
			(at 0.008382 1.210564 180)
			(unlocked yes)
			(layer "F.Fab")
			(hide yes)
			(effects
				(font
					(size 0.7874 0.5842)
					(thickness 0.1524)
				)
			)
		)
		(duplicate_pad_numbers_are_jumpers no)
		(fp_line
			(start 1.143 0.5588)
			(end 1.143 -0.5588)
			(stroke
				(width 0.1)
				(type default)
			)
			(layer "F.SilkS")
		)
		(fp_line
			(start 1.143 -0.5588)
			(end -1.143 -0.5588)
			(stroke
				(width 0.1)
				(type default)
			)
			(layer "F.SilkS")
		)
		(fp_line
			(start -1.143 0.5588)
			(end 1.143 0.5588)
			(stroke
				(width 0.1)
				(type default)
			)
			(layer "F.SilkS")
		)
		(fp_line
			(start -1.143 -0.5588)
			(end -1.143 0.5588)
			(stroke
				(width 0.1)
				(type default)
			)
			(layer "F.SilkS")
		)
		(fp_rect
			(start 1.143 -0.5588)
			(end -1.143 0.5588)
			(stroke
				(width 0)
				(type default)
			)
			(fill no)
			(layer "F.CrtYd")
		)
		(fp_line
			(start 0.508 0.3048)
			(end 0.508 -0.3048)
			(stroke
				(width 0.1)
				(type default)
			)
			(layer "F.Fab")
		)
		(fp_line
			(start 0.508 -0.3048)
			(end -0.508 -0.3048)
			(stroke
				(width 0.1)
				(type default)
			)
			(layer "F.Fab")
		)
		(fp_line
			(start -0.508 0.3048)
			(end 0.508 0.3048)
			(stroke
				(width 0.1)
				(type default)
			)
			(layer "F.Fab")
		)
		(fp_line
			(start -0.508 -0.3048)
			(end -0.508 0.3048)
			(stroke
				(width 0.1)
				(type default)
			)
			(layer "F.Fab")
		)
		(pad "1" smd rect
			(at -0.5334 0 180)
			(size 0.7112 0.6096)
			(layers "F.Cu" "F.Mask" "F.Paste")
			(net "XP3R3V_FPGA")
		)
		(pad "2" smd rect
			(at 0.5334 0 180)
			(size 0.7112 0.6096)
			(layers "F.Cu" "F.Mask" "F.Paste")
			(net "LM75B_I2C_SDA")
		)
		(zone
			(layer "F.Cu")
			(hatch none 0.5)
			(connect_pads
				(clearance 0)
			)
			(min_thickness 0.25)
			(keepout
				(tracks allowed)
				(vias not_allowed)
				(pads allowed)
				(copperpour not_allowed)
				(footprints allowed)
			)
			(placement
				(enabled no)
				(sheetname "")
			)
			(fill
				(thermal_gap 0.5)
				(thermal_bridge_width 0.5)
				(island_removal_mode 0)
			)
			(polygon
				(pts
					(xy 150.6728 -28.2702) (xy 150.8252 -28.2702) (xy 150.8252 -28.8798) (xy 150.6728 -28.8798)
				)
			)
		)
	)
	(footprint ""
		(layer "F.Cu")
		(at 162.56 -27.432 180)
		(property "Reference" "R419"
			(at -2.667 0.72263 0)
			(unlocked yes)
			(layer "F.SilkS")
			(effects
				(font
					(size 0.7874 0.5842)
					(thickness 0.1524)
				)
			)
		)
		(property "Value" "VAL*"
			(at 0.02032 2.13233 180)
			(unlocked yes)
			(layer "F.Fab")
			(hide yes)
			(effects
				(font
					(size 0.7874 0.5842)
					(thickness 0.1524)
				)
			)
		)
		(property "Tolerance" "TOL*"
			(at 0.044704 3.05435 180)
			(unlocked yes)
			(layer "Cmts.User")
			(hide yes)
			(effects
				(font
					(size 0.7874 0.5842)
					(thickness 0.1524)
				)
			)
		)
		(property "User Part Number" "PARTNUM*"
			(at 0.02032 4.024884 180)
			(unlocked yes)
			(layer "Cmts.User")
			(hide yes)
			(effects
				(font
					(size 0.7874 0.5842)
					(thickness 0.1524)
				)
			)
		)
		(property "Device Type" "RESISTOR-G155-14701-01,4.7KOHMA"
			(at 0.008382 1.210564 180)
			(unlocked yes)
			(layer "F.Fab")
			(hide yes)
			(effects
				(font
					(size 0.7874 0.5842)
					(thickness 0.1524)
				)
			)
		)
		(duplicate_pad_numbers_are_jumpers no)
		(fp_line
			(start 1.143 0.5588)
			(end 1.143 -0.5588)
			(stroke
				(width 0.1)
				(type default)
			)
			(layer "F.SilkS")
		)
		(fp_line
			(start 1.143 -0.5588)
			(end -1.143 -0.5588)
			(stroke
				(width 0.1)
				(type default)
			)
			(layer "F.SilkS")
		)
		(fp_line
			(start -1.143 0.5588)
			(end 1.143 0.5588)
			(stroke
				(width 0.1)
				(type default)
			)
			(layer "F.SilkS")
		)
		(fp_line
			(start -1.143 -0.5588)
			(end -1.143 0.5588)
			(stroke
				(width 0.1)
				(type default)
			)
			(layer "F.SilkS")
		)
		(fp_rect
			(start 1.143 -0.5588)
			(end -1.143 0.5588)
			(stroke
				(width 0)
				(type default)
			)
			(fill no)
			(layer "F.CrtYd")
		)
		(fp_line
			(start 0.508 0.3048)
			(end 0.508 -0.3048)
			(stroke
				(width 0.1)
				(type default)
			)
			(layer "F.Fab")
		)
		(fp_line
			(start 0.508 -0.3048)
			(end -0.508 -0.3048)
			(stroke
				(width 0.1)
				(type default)
			)
			(layer "F.Fab")
		)
		(fp_line
			(start -0.508 0.3048)
			(end 0.508 0.3048)
			(stroke
				(width 0.1)
				(type default)
			)
			(layer "F.Fab")
		)
		(fp_line
			(start -0.508 -0.3048)
			(end -0.508 0.3048)
			(stroke
				(width 0.1)
				(type default)
			)
			(layer "F.Fab")
		)
		(pad "1" smd rect
			(at -0.5334 0 180)
			(size 0.7112 0.6096)
			(layers "F.Cu" "F.Mask" "F.Paste")
			(net "XP3R3V_FPGA")
		)
		(pad "2" smd rect
			(at 0.5334 0 180)
			(size 0.7112 0.6096)
			(layers "F.Cu" "F.Mask" "F.Paste")
			(net "UNNAMED_6_LM75BDPTSSOP8_I81_A0")
		)
		(zone
			(layer "F.Cu")
			(hatch none 0.5)
			(connect_pads
				(clearance 0)
			)
			(min_thickness 0.25)
			(keepout
				(tracks not_allowed)
				(vias allowed)
				(pads allowed)
				(copperpour not_allowed)
				(footprints allowed)
			)
			(placement
				(enabled no)
				(sheetname "")
			)
			(fill
				(thermal_gap 0.5)
				(thermal_bridge_width 0.5)
				(island_removal_mode 0)
			)
			(polygon
				(pts
					(xy 162.4838 -27.1272) (xy 162.6362 -27.1272) (xy 162.6362 -27.7368) (xy 162.4838 -27.7368)
				)
			)
		)
		(zone
			(layer "F.Cu")
			(hatch none 0.5)
			(connect_pads
				(clearance 0)
			)
			(min_thickness 0.25)
			(keepout
				(tracks allowed)
				(vias not_allowed)
				(pads allowed)
				(copperpour not_allowed)
				(footprints allowed)
			)
			(placement
				(enabled no)
				(sheetname "")
			)
			(fill
				(thermal_gap 0.5)
				(thermal_bridge_width 0.5)
				(island_removal_mode 0)
			)
			(polygon
				(pts
					(xy 162.4838 -27.1272) (xy 162.6362 -27.1272) (xy 162.6362 -27.7368) (xy 162.4838 -27.7368)
				)
			)
		)
	)
)
